(kicad_pcb
	(version 20260206)
	(generator "pcbnew")
	(generator_version "10.0")
	(general
		(thickness 1.6)
		(legacy_teardrops no)
	)
	(paper "A4")
	(title_block
		(title "03242023_DA0F0TMBIJ0_F0T_Motherboard_J_brd_V01_OCP.brd")
		(comment 1 "Grand Teton / footprint 2126 of 6105 (J112), pads 1-75 of 90")
	)
	(layers
		(0 "F.Cu" signal "TOP")
		(4 "In1.Cu" signal "GND")
		(6 "In2.Cu" signal "IN1")
		(8 "In3.Cu" signal "GND1")
		(10 "In4.Cu" signal "IN2")
		(12 "In5.Cu" signal "GND2")
		(14 "In6.Cu" signal "IN3")
		(16 "In7.Cu" signal "GND3")
		(18 "In8.Cu" signal "VCC")
		(20 "In9.Cu" signal "VCC1")
		(22 "In10.Cu" signal "GND4")
		(24 "In11.Cu" signal "IN4")
		(26 "In12.Cu" signal "GND5")
		(28 "In13.Cu" signal "IN5")
		(30 "In14.Cu" signal "GND6")
		(32 "In15.Cu" signal "IN6")
		(34 "In16.Cu" signal "GND7")
		(2 "B.Cu" signal "BOTTOM")
		(9 "F.Adhes" user "F.Adhesive")
		(11 "B.Adhes" user "B.Adhesive")
		(13 "F.Paste" user "Package Geometry/Pastemask Top")
		(15 "B.Paste" user "Package Geometry/Pastemask Bottom")
		(5 "F.SilkS" user "Ref Des/Silkscreen Top")
		(7 "B.SilkS" user "Ref Des/Silkscreen Bottom")
		(1 "F.Mask" user "Board Geometry/Soldermask Top")
		(3 "B.Mask" user "Board Geometry/Soldermask Bottom")
		(17 "Dwgs.User" user "User.Drawings")
		(19 "Cmts.User" user "User.Comments")
		(21 "Eco1.User" user "User.Eco1")
		(23 "Eco2.User" user "User.Eco2")
		(25 "Edge.Cuts" user "Board Geometry/Outline")
		(27 "Margin" user)
		(31 "F.CrtYd" user "Package Geometry/Place Bound Top")
		(29 "B.CrtYd" user "Package Geometry/Place Bound Bottom")
		(35 "F.Fab" user "Ref Des/Assembly Top")
		(33 "B.Fab" user "Ref Des/Assembly Bottom")
	)
	(footprint ""
		(layer "F.Cu")
		(at 58.650124 -440.489848)
		(property "Reference" "J112"
			(at -7.9883 9.742932 0)
			(unlocked yes)
			(layer "F.SilkS")
			(effects
				(font
					(size 0.7874 0.5842)
					(thickness 0.1524)
				)
				(justify left)
			)
		)
		(property "Value" ""
			(at 0 0 0)
			(layer "F.Fab")
			(effects
				(font
					(size 1.27 1.27)
				)
			)
		)
		(duplicate_pad_numbers_are_jumpers no)
		(pad "A1" thru_hole rect
			(at 0 0 180)
			(size 0.766318 0.766318)
			(drill 0.359918)
			(layers "*.Cu" "*.Mask")
			(remove_unused_layers no)
			(net "RST_PERST_2_SWB_BUF_N")
			(clearance 0.0508)
			(thermal_gap 0.0508)
			(padstack
				(mode front_inner_back)
				(layer "Inner"
					(shape circle)
					(size 0.766318 0.766318)
					(clearance 0.0508)
				)
				(layer "B.Cu"
					(shape rect)
					(size 0.766318 0.766318)
					(clearance 0.0508)
				)
			)
		)
		(pad "A2" thru_hole circle
			(at 1.999996 0.199898 180)
			(size 0.906272 0.906272)
			(drill 0.499872)
			(layers "*.Cu" "*.Mask")
			(remove_unused_layers no)
			(net "GND")
			(clearance 0.0508)
			(thermal_gap 0.0508)
		)
		(pad "A3" thru_hole circle
			(at 3.999992 0 180)
			(size 0.766318 0.766318)
			(drill 0.359918)
			(layers "*.Cu" "*.Mask")
			(remove_unused_layers no)
			(net "HGX_DETECT_N_ISO")
			(clearance 0.0508)
			(thermal_gap 0.0508)
		)
		(pad "A4" thru_hole circle
			(at 5.999988 0.199898 180)
			(size 0.906272 0.906272)
			(drill 0.499872)
			(layers "*.Cu" "*.Mask")
			(remove_unused_layers no)
			(net "GND")
			(clearance 0.0508)
			(thermal_gap 0.0508)
		)
		(pad "A5" thru_hole circle
			(at 7.999984 0 180)
			(size 0.766318 0.766318)
			(drill 0.359918)
			(layers "*.Cu" "*.Mask")
			(remove_unused_layers no)
			(net "RST_PERST_1_SWB_BUF_N")
			(clearance 0.0508)
			(thermal_gap 0.0508)
		)
		(pad "A6" thru_hole circle
			(at 9.99998 0.199898 180)
			(size 0.906272 0.906272)
			(drill 0.499872)
			(layers "*.Cu" "*.Mask")
			(remove_unused_layers no)
			(net "GND")
			(clearance 0.0508)
			(thermal_gap 0.0508)
		)
		(pad "A7" thru_hole circle
			(at 11.999976 0 180)
			(size 0.766318 0.766318)
			(drill 0.359918)
			(layers "*.Cu" "*.Mask")
			(remove_unused_layers no)
			(net "PRSNT_SWB_N")
			(clearance 0.0508)
			(thermal_gap 0.0508)
		)
		(pad "A8" thru_hole circle
			(at 13.999972 0.199898 180)
			(size 0.906272 0.906272)
			(drill 0.499872)
			(layers "*.Cu" "*.Mask")
			(remove_unused_layers no)
			(net "GND")
			(clearance 0.0508)
			(thermal_gap 0.0508)
		)
		(pad "B1" thru_hole circle
			(at 0 1.199896 180)
			(size 0.906272 0.906272)
			(drill 0.499872)
			(layers "*.Cu" "*.Mask")
			(remove_unused_layers no)
			(net "GND")
			(clearance 0.0508)
			(thermal_gap 0.0508)
		)
		(pad "B3" thru_hole circle
			(at 3.999992 1.199896 180)
			(size 0.906272 0.906272)
			(drill 0.499872)
			(layers "*.Cu" "*.Mask")
			(remove_unused_layers no)
			(net "GND")
			(clearance 0.0508)
			(thermal_gap 0.0508)
		)
		(pad "B5" thru_hole circle
			(at 7.999984 1.199896 180)
			(size 0.906272 0.906272)
			(drill 0.499872)
			(layers "*.Cu" "*.Mask")
			(remove_unused_layers no)
			(net "GND")
			(clearance 0.0508)
			(thermal_gap 0.0508)
		)
		(pad "B7" thru_hole circle
			(at 11.999976 1.199896 180)
			(size 0.906272 0.906272)
			(drill 0.499872)
			(layers "*.Cu" "*.Mask")
			(remove_unused_layers no)
			(net "GND")
			(clearance 0.0508)
			(thermal_gap 0.0508)
		)
		(pad "D2" thru_hole circle
			(at 1.999996 3.800094 180)
			(size 0.906272 0.906272)
			(drill 0.499872)
			(layers "*.Cu" "*.Mask")
			(remove_unused_layers no)
			(net "GND")
			(clearance 0.0508)
			(thermal_gap 0.0508)
		)
		(pad "D4" thru_hole circle
			(at 5.999988 3.800094 180)
			(size 0.906272 0.906272)
			(drill 0.499872)
			(layers "*.Cu" "*.Mask")
			(remove_unused_layers no)
			(net "GND")
			(clearance 0.0508)
			(thermal_gap 0.0508)
		)
		(pad "D6" thru_hole circle
			(at 9.99998 3.800094 180)
			(size 0.906272 0.906272)
			(drill 0.499872)
			(layers "*.Cu" "*.Mask")
			(remove_unused_layers no)
			(net "GND")
			(clearance 0.0508)
			(thermal_gap 0.0508)
		)
		(pad "D8" thru_hole circle
			(at 13.999972 3.800094 180)
			(size 0.906272 0.906272)
			(drill 0.499872)
			(layers "*.Cu" "*.Mask")
			(remove_unused_layers no)
			(net "GND")
			(clearance 0.0508)
			(thermal_gap 0.0508)
		)
		(pad "E1" thru_hole circle
			(at 0 4.800092 180)
			(size 0.906272 0.906272)
			(drill 0.499872)
			(layers "*.Cu" "*.Mask")
			(remove_unused_layers no)
			(net "GND")
			(clearance 0.0508)
			(thermal_gap 0.0508)
		)
		(pad "E3" thru_hole circle
			(at 3.999992 4.800092 180)
			(size 0.906272 0.906272)
			(drill 0.499872)
			(layers "*.Cu" "*.Mask")
			(remove_unused_layers no)
			(net "GND")
			(clearance 0.0508)
			(thermal_gap 0.0508)
		)
		(pad "E5" thru_hole circle
			(at 7.999984 4.800092 180)
			(size 0.906272 0.906272)
			(drill 0.499872)
			(layers "*.Cu" "*.Mask")
			(remove_unused_layers no)
			(net "GND")
			(clearance 0.0508)
			(thermal_gap 0.0508)
		)
		(pad "E7" thru_hole circle
			(at 11.999976 4.800092 180)
			(size 0.906272 0.906272)
			(drill 0.499872)
			(layers "*.Cu" "*.Mask")
			(remove_unused_layers no)
			(net "GND")
			(clearance 0.0508)
			(thermal_gap 0.0508)
		)
		(pad "G2" thru_hole circle
			(at 1.999996 7.400036 180)
			(size 0.906272 0.906272)
			(drill 0.499872)
			(layers "*.Cu" "*.Mask")
			(remove_unused_layers no)
			(net "GND")
			(clearance 0.0508)
			(thermal_gap 0.0508)
		)
		(pad "G4" thru_hole circle
			(at 5.999988 7.400036 180)
			(size 0.906272 0.906272)
			(drill 0.499872)
			(layers "*.Cu" "*.Mask")
			(remove_unused_layers no)
			(net "GND")
			(clearance 0.0508)
			(thermal_gap 0.0508)
		)
		(pad "G6" thru_hole circle
			(at 9.99998 7.400036 180)
			(size 0.906272 0.906272)
			(drill 0.499872)
			(layers "*.Cu" "*.Mask")
			(remove_unused_layers no)
			(net "GND")
			(clearance 0.0508)
			(thermal_gap 0.0508)
		)
		(pad "G8" thru_hole circle
			(at 13.999972 7.400036 180)
			(size 0.906272 0.906272)
			(drill 0.499872)
			(layers "*.Cu" "*.Mask")
			(remove_unused_layers no)
			(net "GND")
			(clearance 0.0508)
			(thermal_gap 0.0508)
		)
		(pad "H1" thru_hole circle
			(at 0 8.400034 180)
			(size 0.906272 0.906272)
			(drill 0.499872)
			(layers "*.Cu" "*.Mask")
			(remove_unused_layers no)
			(net "GND")
			(clearance 0.0508)
			(thermal_gap 0.0508)
		)
		(pad "H3" thru_hole circle
			(at 3.999992 8.400034 180)
			(size 0.906272 0.906272)
			(drill 0.499872)
			(layers "*.Cu" "*.Mask")
			(remove_unused_layers no)
			(net "GND")
			(clearance 0.0508)
			(thermal_gap 0.0508)
		)
		(pad "H5" thru_hole circle
			(at 7.999984 8.400034 180)
			(size 0.906272 0.906272)
			(drill 0.499872)
			(layers "*.Cu" "*.Mask")
			(remove_unused_layers no)
			(net "GND")
			(clearance 0.0508)
			(thermal_gap 0.0508)
		)
		(pad "H7" thru_hole circle
			(at 11.999976 8.400034 180)
			(size 0.906272 0.906272)
			(drill 0.499872)
			(layers "*.Cu" "*.Mask")
			(remove_unused_layers no)
			(net "GND")
			(clearance 0.0508)
			(thermal_gap 0.0508)
		)
		(pad "J2" thru_hole circle
			(at 1.999996 10.999978 180)
			(size 0.906272 0.906272)
			(drill 0.499872)
			(layers "*.Cu" "*.Mask")
			(remove_unused_layers no)
			(net "GND")
			(clearance 0.0508)
			(thermal_gap 0.0508)
		)
		(pad "J4" thru_hole circle
			(at 5.999988 10.999978 180)
			(size 0.906272 0.906272)
			(drill 0.499872)
			(layers "*.Cu" "*.Mask")
			(remove_unused_layers no)
			(net "GND")
			(clearance 0.0508)
			(thermal_gap 0.0508)
		)
		(pad "J6" thru_hole circle
			(at 9.99998 10.999978 180)
			(size 0.906272 0.906272)
			(drill 0.499872)
			(layers "*.Cu" "*.Mask")
			(remove_unused_layers no)
			(net "GND")
			(clearance 0.0508)
			(thermal_gap 0.0508)
		)
		(pad "J8" thru_hole circle
			(at 13.999972 10.999978 180)
			(size 0.906272 0.906272)
			(drill 0.499872)
			(layers "*.Cu" "*.Mask")
			(remove_unused_layers no)
			(net "GND")
			(clearance 0.0508)
			(thermal_gap 0.0508)
		)
		(pad "K1" thru_hole circle
			(at 0 11.999976 180)
			(size 0.906272 0.906272)
			(drill 0.499872)
			(layers "*.Cu" "*.Mask")
			(remove_unused_layers no)
			(net "GND")
			(clearance 0.0508)
			(thermal_gap 0.0508)
		)
		(pad "K3" thru_hole circle
			(at 3.999992 11.999976 180)
			(size 0.906272 0.906272)
			(drill 0.499872)
			(layers "*.Cu" "*.Mask")
			(remove_unused_layers no)
			(net "GND")
			(clearance 0.0508)
			(thermal_gap 0.0508)
		)
		(pad "K5" thru_hole circle
			(at 7.999984 11.999976 180)
			(size 0.906272 0.906272)
			(drill 0.499872)
			(layers "*.Cu" "*.Mask")
			(remove_unused_layers no)
			(net "GND")
			(clearance 0.0508)
			(thermal_gap 0.0508)
		)
		(pad "K7" thru_hole circle
			(at 11.999976 11.999976 180)
			(size 0.906272 0.906272)
			(drill 0.499872)
			(layers "*.Cu" "*.Mask")
			(remove_unused_layers no)
			(net "GND")
			(clearance 0.0508)
			(thermal_gap 0.0508)
		)
		(pad "M2" thru_hole circle
			(at 1.999996 14.59992 180)
			(size 0.906272 0.906272)
			(drill 0.499872)
			(layers "*.Cu" "*.Mask")
			(remove_unused_layers no)
			(net "GND")
			(clearance 0.0508)
			(thermal_gap 0.0508)
		)
		(pad "M4" thru_hole circle
			(at 5.999988 14.59992 180)
			(size 0.906272 0.906272)
			(drill 0.499872)
			(layers "*.Cu" "*.Mask")
			(remove_unused_layers no)
			(net "GND")
			(clearance 0.0508)
			(thermal_gap 0.0508)
		)
		(pad "M6" thru_hole circle
			(at 9.99998 14.59992 180)
			(size 0.906272 0.906272)
			(drill 0.499872)
			(layers "*.Cu" "*.Mask")
			(remove_unused_layers no)
			(net "GND")
			(clearance 0.0508)
			(thermal_gap 0.0508)
		)
		(pad "M8" thru_hole circle
			(at 13.999972 14.59992 180)
			(size 0.906272 0.906272)
			(drill 0.499872)
			(layers "*.Cu" "*.Mask")
			(remove_unused_layers no)
			(net "GND")
			(clearance 0.0508)
			(thermal_gap 0.0508)
		)
		(pad "N1" thru_hole circle
			(at 0 15.599918 180)
			(size 0.906272 0.906272)
			(drill 0.499872)
			(layers "*.Cu" "*.Mask")
			(remove_unused_layers no)
			(net "GND")
			(clearance 0.0508)
			(thermal_gap 0.0508)
		)
		(pad "N2" thru_hole circle
			(at 1.999996 15.80007 180)
			(size 0.766318 0.766318)
			(drill 0.359918)
			(layers "*.Cu" "*.Mask")
			(remove_unused_layers no)
			(net "NC_J112_N2")
			(clearance 0.0508)
			(thermal_gap 0.0508)
		)
		(pad "N3" thru_hole circle
			(at 3.999992 15.599918 180)
			(size 0.906272 0.906272)
			(drill 0.499872)
			(layers "*.Cu" "*.Mask")
			(remove_unused_layers no)
			(net "GND")
			(clearance 0.0508)
			(thermal_gap 0.0508)
		)
		(pad "N4" thru_hole circle
			(at 5.999988 15.80007 180)
			(size 0.766318 0.766318)
			(drill 0.359918)
			(layers "*.Cu" "*.Mask")
			(remove_unused_layers no)
			(net "CLK_100M_GPU_1_DN")
			(clearance 0.0508)
			(thermal_gap 0.0508)
		)
		(pad "N5" thru_hole circle
			(at 7.999984 15.599918 180)
			(size 0.906272 0.906272)
			(drill 0.499872)
			(layers "*.Cu" "*.Mask")
			(remove_unused_layers no)
			(net "GND")
			(clearance 0.0508)
			(thermal_gap 0.0508)
		)
		(pad "N6" thru_hole circle
			(at 9.99998 15.80007 180)
			(size 0.766318 0.766318)
			(drill 0.359918)
			(layers "*.Cu" "*.Mask")
			(remove_unused_layers no)
			(net "P2E_MB_BMC_RX_DN<0>")
			(clearance 0.0508)
			(thermal_gap 0.0508)
		)
		(pad "N7" thru_hole circle
			(at 11.999976 15.599918 180)
			(size 0.906272 0.906272)
			(drill 0.499872)
			(layers "*.Cu" "*.Mask")
			(remove_unused_layers no)
			(net "GND")
			(clearance 0.0508)
			(thermal_gap 0.0508)
		)
		(pad "O1" thru_hole circle
			(at 0 16.800068 180)
			(size 0.766318 0.766318)
			(drill 0.359918)
			(layers "*.Cu" "*.Mask")
			(remove_unused_layers no)
			(net "CLK_100M_GPU_2_DN")
			(clearance 0.0508)
			(thermal_gap 0.0508)
		)
		(pad "O2" thru_hole circle
			(at 1.999996 16.999966 180)
			(size 0.766318 0.766318)
			(drill 0.359918)
			(layers "*.Cu" "*.Mask")
			(remove_unused_layers no)
			(net "NC_J112_O2")
			(clearance 0.0508)
			(thermal_gap 0.0508)
		)
		(pad "O3" thru_hole circle
			(at 3.999992 16.800068 180)
			(size 0.766318 0.766318)
			(drill 0.359918)
			(layers "*.Cu" "*.Mask")
			(remove_unused_layers no)
			(net "CLK_100M_SWB_DN")
			(clearance 0.0508)
			(thermal_gap 0.0508)
		)
		(pad "O4" thru_hole circle
			(at 5.999988 16.999966 180)
			(size 0.766318 0.766318)
			(drill 0.359918)
			(layers "*.Cu" "*.Mask")
			(remove_unused_layers no)
			(net "CLK_100M_GPU_1_DP")
			(clearance 0.0508)
			(thermal_gap 0.0508)
		)
		(pad "O5" thru_hole circle
			(at 7.999984 16.800068 180)
			(size 0.766318 0.766318)
			(drill 0.359918)
			(layers "*.Cu" "*.Mask")
			(remove_unused_layers no)
			(net "NC_J112_O5")
			(clearance 0.0508)
			(thermal_gap 0.0508)
		)
		(pad "O6" thru_hole circle
			(at 9.99998 16.999966 180)
			(size 0.766318 0.766318)
			(drill 0.359918)
			(layers "*.Cu" "*.Mask")
			(remove_unused_layers no)
			(net "P2E_MB_BMC_RX_DP<0>")
			(clearance 0.0508)
			(thermal_gap 0.0508)
		)
		(pad "O7" thru_hole circle
			(at 11.999976 16.800068 180)
			(size 0.766318 0.766318)
			(drill 0.359918)
			(layers "*.Cu" "*.Mask")
			(remove_unused_layers no)
			(net "P3E_PCH_NVS_RX_DN<1>")
			(clearance 0.0508)
			(thermal_gap 0.0508)
		)
		(pad "P1" thru_hole circle
			(at 0 17.999964 180)
			(size 0.766318 0.766318)
			(drill 0.359918)
			(layers "*.Cu" "*.Mask")
			(remove_unused_layers no)
			(net "CLK_100M_GPU_2_DP")
			(clearance 0.0508)
			(thermal_gap 0.0508)
		)
		(pad "P2" thru_hole circle
			(at 1.999996 18.200116 180)
			(size 0.906272 0.906272)
			(drill 0.499872)
			(layers "*.Cu" "*.Mask")
			(remove_unused_layers no)
			(net "GND")
			(clearance 0.0508)
			(thermal_gap 0.0508)
		)
		(pad "P3" thru_hole circle
			(at 3.999992 17.999964 180)
			(size 0.766318 0.766318)
			(drill 0.359918)
			(layers "*.Cu" "*.Mask")
			(remove_unused_layers no)
			(net "CLK_100M_SWB_DP")
			(clearance 0.0508)
			(thermal_gap 0.0508)
		)
		(pad "P4" thru_hole circle
			(at 5.999988 18.200116 180)
			(size 0.906272 0.906272)
			(drill 0.499872)
			(layers "*.Cu" "*.Mask")
			(remove_unused_layers no)
			(net "GND")
			(clearance 0.0508)
			(thermal_gap 0.0508)
		)
		(pad "P5" thru_hole circle
			(at 7.999984 17.999964 180)
			(size 0.766318 0.766318)
			(drill 0.359918)
			(layers "*.Cu" "*.Mask")
			(remove_unused_layers no)
			(net "NC_J112_P5")
			(clearance 0.0508)
			(thermal_gap 0.0508)
		)
		(pad "P6" thru_hole circle
			(at 9.99998 18.200116 180)
			(size 0.906272 0.906272)
			(drill 0.499872)
			(layers "*.Cu" "*.Mask")
			(remove_unused_layers no)
			(net "GND")
			(clearance 0.0508)
			(thermal_gap 0.0508)
		)
		(pad "P7" thru_hole circle
			(at 11.999976 17.999964 180)
			(size 0.766318 0.766318)
			(drill 0.359918)
			(layers "*.Cu" "*.Mask")
			(remove_unused_layers no)
			(net "P3E_PCH_NVS_RX_DP<1>")
			(clearance 0.0508)
			(thermal_gap 0.0508)
		)
		(pad "P8" thru_hole circle
			(at 13.999972 18.200116 180)
			(size 0.906272 0.906272)
			(drill 0.499872)
			(layers "*.Cu" "*.Mask")
			(remove_unused_layers no)
			(net "GND")
			(clearance 0.0508)
			(thermal_gap 0.0508)
		)
		(pad "Q1" thru_hole circle
			(at 0 19.200114 180)
			(size 0.906272 0.906272)
			(drill 0.499872)
			(layers "*.Cu" "*.Mask")
			(remove_unused_layers no)
			(net "GND")
			(clearance 0.0508)
			(thermal_gap 0.0508)
		)
		(pad "Q2" thru_hole circle
			(at 1.999996 19.400012 180)
			(size 0.766318 0.766318)
			(drill 0.359918)
			(layers "*.Cu" "*.Mask")
			(remove_unused_layers no)
			(net "CLK_100M_GPU_FPGA_DN")
			(clearance 0.0508)
			(thermal_gap 0.0508)
		)
		(pad "Q3" thru_hole circle
			(at 3.999992 19.200114 180)
			(size 0.906272 0.906272)
			(drill 0.499872)
			(layers "*.Cu" "*.Mask")
			(remove_unused_layers no)
			(net "GND")
			(clearance 0.0508)
			(thermal_gap 0.0508)
		)
		(pad "Q4" thru_hole circle
			(at 5.999988 19.400012 180)
			(size 0.766318 0.766318)
			(drill 0.359918)
			(layers "*.Cu" "*.Mask")
			(remove_unused_layers no)
			(net "SMB_1_BMC_GPU_BUF_SCL")
			(clearance 0.0508)
			(thermal_gap 0.0508)
		)
		(pad "Q5" thru_hole circle
			(at 7.999984 19.200114 180)
			(size 0.906272 0.906272)
			(drill 0.499872)
			(layers "*.Cu" "*.Mask")
			(remove_unused_layers no)
			(net "GND")
			(clearance 0.0508)
			(thermal_gap 0.0508)
		)
		(pad "Q7" thru_hole circle
			(at 11.999976 19.200114 180)
			(size 0.906272 0.906272)
			(drill 0.499872)
			(layers "*.Cu" "*.Mask")
			(remove_unused_layers no)
			(net "GND")
			(clearance 0.0508)
			(thermal_gap 0.0508)
		)
		(pad "R1" thru_hole circle
			(at 0 20.40001 180)
			(size 0.766318 0.766318)
			(drill 0.359918)
			(layers "*.Cu" "*.Mask")
			(remove_unused_layers no)
			(net "USB2_HUB_BUF_SWB_DN")
			(clearance 0.0508)
			(thermal_gap 0.0508)
		)
		(pad "R2" thru_hole circle
			(at 1.999996 20.599908 180)
			(size 0.766318 0.766318)
			(drill 0.359918)
			(layers "*.Cu" "*.Mask")
			(remove_unused_layers no)
			(net "CLK_100M_GPU_FPGA_DP")
			(clearance 0.0508)
			(thermal_gap 0.0508)
		)
		(pad "R3" thru_hole circle
			(at 3.999992 20.40001 180)
			(size 0.766318 0.766318)
			(drill 0.359918)
			(layers "*.Cu" "*.Mask")
			(remove_unused_layers no)
			(net "SMB_2_BMC_GPU_BUF_SCL")
			(clearance 0.0508)
			(thermal_gap 0.0508)
		)
		(pad "R4" thru_hole circle
			(at 5.999988 20.599908 180)
			(size 0.766318 0.766318)
			(drill 0.359918)
			(layers "*.Cu" "*.Mask")
			(remove_unused_layers no)
			(net "SMB_1_BMC_GPU_BUF_SDA")
			(clearance 0.0508)
			(thermal_gap 0.0508)
		)
		(pad "R5" thru_hole circle
			(at 7.999984 20.40001 180)
			(size 0.766318 0.766318)
			(drill 0.359918)
			(layers "*.Cu" "*.Mask")
			(remove_unused_layers no)
			(net "NC_J112_R5")
			(clearance 0.0508)
			(thermal_gap 0.0508)
		)
		(pad "R7" thru_hole circle
			(at 11.999976 20.40001 180)
			(size 0.766318 0.766318)
			(drill 0.359918)
			(layers "*.Cu" "*.Mask")
			(remove_unused_layers no)
			(net "P3E_PCH_NVS_TX_C_DN<1>")
			(clearance 0.0508)
			(thermal_gap 0.0508)
		)
		(pad "S1" thru_hole circle
			(at 0 21.599906 180)
			(size 0.766318 0.766318)
			(drill 0.359918)
			(layers "*.Cu" "*.Mask")
			(remove_unused_layers no)
			(net "USB2_HUB_BUF_SWB_DP")
			(clearance 0.0508)
			(thermal_gap 0.0508)
		)
	)
)
